# T6G (Grand Teton) — schematic netlist excerpt (pin names and nets, part order shuffled) for the footprints in the layout excerpt that follows; sources: Cadence DE-HDL packaged netlist, KiCad conversion of 04192023_DAF0TMB3IC0_F0TG_MB_C_brd_V02_OCP.brd

R6309  Q_RES  200K 1% CHIP  pkg 0402LF  page 179 : A = USB_HUB2_MRP_CFG_NON_REM ; B = GND
C709  Q_CAP_DIFFBUS  DIFF BUS_0.22UF 6.3V 20% X6S  pkg C0201  page 67 : \1\ = P5E_CPU1_G1_TX_C_DP<0> ; \2\ = P5E_CPU1_G1_TX_DP<0>
R8095  Q_RES  10K 5% EMPTY  pkg 0402LF  page 142 : A = P3V3_OCP_V3_2_R ; B = OCP_V3_2_P3V3_R1_PWRGD

(kicad_pcb
	(version 20260206)
	(generator "pcbnew")
	(generator_version "10.0")
	(general
		(thickness 1.6)
		(legacy_teardrops no)
	)
	(paper "A4")
	(title_block
		(title "04192023_DAF0TMB3IC0_F0TG_MB_C_brd_V02_OCP.brd")
		(comment 1 "Grand Teton / footprints 4461-4463 of 8354")
	)
	(layers
		(0 "F.Cu" signal "TOP")
		(4 "In1.Cu" signal "GND")
		(6 "In2.Cu" signal "IN1")
		(8 "In3.Cu" signal "GND1")
		(10 "In4.Cu" signal "IN2")
		(12 "In5.Cu" signal "GND2")
		(14 "In6.Cu" signal "IN3")
		(16 "In7.Cu" signal "GND3")
		(18 "In8.Cu" signal "VCC")
		(20 "In9.Cu" signal "VCC1")
		(22 "In10.Cu" signal "GND4")
		(24 "In11.Cu" signal "IN4")
		(26 "In12.Cu" signal "GND5")
		(28 "In13.Cu" signal "IN5")
		(30 "In14.Cu" signal "GND6")
		(32 "In15.Cu" signal "IN6")
		(34 "In16.Cu" signal "GND7")
		(2 "B.Cu" signal "BOTTOM")
		(9 "F.Adhes" user "F.Adhesive")
		(11 "B.Adhes" user "B.Adhesive")
		(13 "F.Paste" user "Package Geometry/Pastemask Top")
		(15 "B.Paste" user "Package Geometry/Pastemask Bottom")
		(5 "F.SilkS" user "Ref Des/Silkscreen Top")
		(7 "B.SilkS" user "Ref Des/Silkscreen Bottom")
		(1 "F.Mask" user "Board Geometry/Soldermask Top")
		(3 "B.Mask" user "Board Geometry/Soldermask Bottom")
		(17 "Dwgs.User" user "User.Drawings")
		(19 "Cmts.User" user "User.Comments")
		(21 "Eco1.User" user "User.Eco1")
		(23 "Eco2.User" user "User.Eco2")
		(25 "Edge.Cuts" user "Board Geometry/Outline")
		(27 "Margin" user)
		(31 "F.CrtYd" user "Package Geometry/Place Bound Top")
		(29 "B.CrtYd" user "Package Geometry/Place Bound Bottom")
		(35 "F.Fab" user "Ref Des/Assembly Top")
		(33 "B.Fab" user "Ref Des/Assembly Bottom")
	)
	(footprint ""
		(layer "F.Cu")
		(at 76.835 -64.008 90)
		(property "Reference" "R8095"
			(at 0 0 90)
			(layer "F.SilkS")
			(hide yes)
			(effects
				(font
					(size 1.27 1.27)
				)
			)
		)
		(property "Value" ""
			(at 0 0 90)
			(layer "F.Fab")
			(effects
				(font
					(size 1.27 1.27)
				)
			)
		)
		(duplicate_pad_numbers_are_jumpers no)
		(fp_line
			(start 0.7874 -0.4064)
			(end 0.7874 0.4064)
			(stroke
				(width 0.1524)
				(type default)
			)
			(layer "F.SilkS")
		)
		(fp_line
			(start -0.7874 -0.4064)
			(end 0.7874 -0.4064)
			(stroke
				(width 0.1524)
				(type default)
			)
			(layer "F.SilkS")
		)
		(fp_line
			(start 0.7874 0.4064)
			(end -0.7874 0.4064)
			(stroke
				(width 0.1524)
				(type default)
			)
			(layer "F.SilkS")
		)
		(fp_line
			(start -0.7874 0.4064)
			(end -0.7874 -0.4064)
			(stroke
				(width 0.1524)
				(type default)
			)
			(layer "F.SilkS")
		)
		(fp_line
			(start -0.12065 -0.305054)
			(end -0.12065 -0.2794)
			(stroke
				(width 0.1)
				(type default)
			)
			(layer "F.Fab")
		)
		(fp_line
			(start -0.67945 -0.305054)
			(end -0.12065 -0.305054)
			(stroke
				(width 0.1)
				(type default)
			)
			(layer "F.Fab")
		)
		(fp_line
			(start 0.67945 -0.3048)
			(end 0.67945 0.3048)
			(stroke
				(width 0.1)
				(type default)
			)
			(layer "F.Fab")
		)
		(fp_line
			(start 0.12065 -0.3048)
			(end 0.67945 -0.3048)
			(stroke
				(width 0.1)
				(type default)
			)
			(layer "F.Fab")
		)
		(fp_line
			(start 0.12065 -0.2794)
			(end 0.12065 -0.3048)
			(stroke
				(width 0.1)
				(type default)
			)
			(layer "F.Fab")
		)
		(fp_line
			(start -0.12065 -0.2794)
			(end 0.12065 -0.2794)
			(stroke
				(width 0.1)
				(type default)
			)
			(layer "F.Fab")
		)
		(fp_line
			(start 0.120396 0.2794)
			(end -0.12065 0.2794)
			(stroke
				(width 0.1)
				(type default)
			)
			(layer "F.Fab")
		)
		(fp_line
			(start -0.12065 0.2794)
			(end -0.12065 0.3048)
			(stroke
				(width 0.1)
				(type default)
			)
			(layer "F.Fab")
		)
		(fp_line
			(start 0.67945 0.3048)
			(end 0.120396 0.3048)
			(stroke
				(width 0.1)
				(type default)
			)
			(layer "F.Fab")
		)
		(fp_line
			(start 0.120396 0.3048)
			(end 0.120396 0.2794)
			(stroke
				(width 0.1)
				(type default)
			)
			(layer "F.Fab")
		)
		(fp_line
			(start -0.12065 0.3048)
			(end -0.67945 0.3048)
			(stroke
				(width 0.1)
				(type default)
			)
			(layer "F.Fab")
		)
		(fp_line
			(start -0.67945 0.3048)
			(end -0.67945 -0.305054)
			(stroke
				(width 0.1)
				(type default)
			)
			(layer "F.Fab")
		)
		(pad "1" smd circle
			(at -0.40005 0 90)
			(size 0 0)
			(layers "F.Cu" "F.Mask" "F.Paste")
			(net "P3V3_OCP_V3_2_R")
		)
		(pad "2" smd circle
			(at 0.40005 0 90)
			(size 0 0)
			(layers "F.Cu" "F.Mask" "F.Paste")
			(net "OCP_V3_2_P3V3_R1_PWRGD")
		)
	)
	(footprint ""
		(layer "F.Cu")
		(at 58.67273 -17.623536 90)
		(property "Reference" "C709"
			(at 0 0 90)
			(layer "F.SilkS")
			(hide yes)
			(effects
				(font
					(size 1.27 1.27)
				)
			)
		)
		(property "Value" ""
			(at 0 0 90)
			(layer "F.Fab")
			(effects
				(font
					(size 1.27 1.27)
				)
			)
		)
		(duplicate_pad_numbers_are_jumpers no)
		(fp_line
			(start 0.299974 -0.150114)
			(end 0.299974 0.150114)
			(stroke
				(width 0.1)
				(type default)
			)
			(layer "F.Fab")
		)
		(fp_line
			(start -0.299974 -0.150114)
			(end 0.299974 -0.150114)
			(stroke
				(width 0.1)
				(type default)
			)
			(layer "F.Fab")
		)
		(fp_line
			(start 0.299974 0.150114)
			(end -0.299974 0.150114)
			(stroke
				(width 0.1)
				(type default)
			)
			(layer "F.Fab")
		)
		(fp_line
			(start -0.299974 0.150114)
			(end -0.299974 -0.150114)
			(stroke
				(width 0.1)
				(type default)
			)
			(layer "F.Fab")
		)
		(pad "1" smd rect
			(at -0.2667 0 90)
			(size 0.3048 0.381)
			(layers "F.Cu" "F.Mask" "F.Paste")
			(net "P5E_CPU1_G1_TX_C_DP<0>")
		)
		(pad "2" smd rect
			(at 0.2667 0 90)
			(size 0.3048 0.381)
			(layers "F.Cu" "F.Mask" "F.Paste")
			(net "P5E_CPU1_G1_TX_DP<0>")
		)
	)
	(footprint ""
		(layer "F.Cu")
		(at 111.581946 -54.882034 90)
		(property "Reference" "R6309"
			(at 0 0 90)
			(layer "F.SilkS")
			(hide yes)
			(effects
				(font
					(size 1.27 1.27)
				)
			)
		)
		(property "Value" ""
			(at 0 0 90)
			(layer "F.Fab")
			(effects
				(font
					(size 1.27 1.27)
				)
			)
		)
		(duplicate_pad_numbers_are_jumpers no)
		(fp_line
			(start 0.7874 -0.4064)
			(end 0.7874 0.4064)
			(stroke
				(width 0.1524)
				(type default)
			)
			(layer "F.SilkS")
		)
		(fp_line
			(start -0.7874 -0.4064)
			(end 0.7874 -0.4064)
			(stroke
				(width 0.1524)
				(type default)
			)
			(layer "F.SilkS")
		)
		(fp_line
			(start 0.7874 0.4064)
			(end -0.7874 0.4064)
			(stroke
				(width 0.1524)
				(type default)
			)
			(layer "F.SilkS")
		)
		(fp_line
			(start -0.7874 0.4064)
			(end -0.7874 -0.4064)
			(stroke
				(width 0.1524)
				(type default)
			)
			(layer "F.SilkS")
		)
		(fp_line
			(start -0.12065 -0.305054)
			(end -0.12065 -0.2794)
			(stroke
				(width 0.1)
				(type default)
			)
			(layer "F.Fab")
		)
		(fp_line
			(start -0.67945 -0.305054)
			(end -0.12065 -0.305054)
			(stroke
				(width 0.1)
				(type default)
			)
			(layer "F.Fab")
		)
		(fp_line
			(start 0.67945 -0.3048)
			(end 0.67945 0.3048)
			(stroke
				(width 0.1)
				(type default)
			)
			(layer "F.Fab")
		)
		(fp_line
			(start 0.12065 -0.3048)
			(end 0.67945 -0.3048)
			(stroke
				(width 0.1)
				(type default)
			)
			(layer "F.Fab")
		)
		(fp_line
			(start 0.12065 -0.2794)
			(end 0.12065 -0.3048)
			(stroke
				(width 0.1)
				(type default)
			)
			(layer "F.Fab")
		)
		(fp_line
			(start -0.12065 -0.2794)
			(end 0.12065 -0.2794)
			(stroke
				(width 0.1)
				(type default)
			)
			(layer "F.Fab")
		)
		(fp_line
			(start 0.120396 0.2794)
			(end -0.12065 0.2794)
			(stroke
				(width 0.1)
				(type default)
			)
			(layer "F.Fab")
		)
		(fp_line
			(start -0.12065 0.2794)
			(end -0.12065 0.3048)
			(stroke
				(width 0.1)
				(type default)
			)
			(layer "F.Fab")
		)
		(fp_line
			(start 0.67945 0.3048)
			(end 0.120396 0.3048)
			(stroke
				(width 0.1)
				(type default)
			)
			(layer "F.Fab")
		)
		(fp_line
			(start 0.120396 0.3048)
			(end 0.120396 0.2794)
			(stroke
				(width 0.1)
				(type default)
			)
			(layer "F.Fab")
		)
		(fp_line
			(start -0.12065 0.3048)
			(end -0.67945 0.3048)
			(stroke
				(width 0.1)
				(type default)
			)
			(layer "F.Fab")
		)
		(fp_line
			(start -0.67945 0.3048)
			(end -0.67945 -0.305054)
			(stroke
				(width 0.1)
				(type default)
			)
			(layer "F.Fab")
		)
		(pad "1" smd circle
			(at -0.40005 0 90)
			(size 0 0)
			(layers "F.Cu" "F.Mask" "F.Paste")
			(net "USB_HUB2_MRP_CFG_NON_REM")
		)
		(pad "2" smd circle
			(at 0.40005 0 90)
			(size 0 0)
			(layers "F.Cu" "F.Mask" "F.Paste")
			(net "GND")
		)
	)
)
